# S9S_MB_2U (Grand Teton) — schematic netlist excerpt (pin names and nets, part order shuffled) for the footprints in the layout excerpt that follows; sources: Cadence DE-HDL packaged netlist, KiCad conversion of 03242023_DA0F0TMBIJ0_F0T_Motherboard_J_brd_V01_OCP.brd

J116  PICOPROBE_BXA  DELTA-L 4.0 EMPTY  pkg TRIANG_LAUNCH_3PXB  page 308
  \1_p\  = DELTA_L_85_5INCH_IN5_DN
  \2_n\  = DELTA_L_85_5INCH_IN5_DP
  \3_g\  = DELTA_L_GND_1

(kicad_pcb
	(version 20260206)
	(generator "pcbnew")
	(generator_version "10.0")
	(general
		(thickness 1.6)
		(legacy_teardrops no)
	)
	(paper "A4")
	(title_block
		(title "03242023_DA0F0TMBIJ0_F0T_Motherboard_J_brd_V01_OCP.brd")
		(comment 1 "Grand Teton / footprints 4379-4379 of 6105")
	)
	(layers
		(0 "F.Cu" signal "TOP")
		(4 "In1.Cu" signal "GND")
		(6 "In2.Cu" signal "IN1")
		(8 "In3.Cu" signal "GND1")
		(10 "In4.Cu" signal "IN2")
		(12 "In5.Cu" signal "GND2")
		(14 "In6.Cu" signal "IN3")
		(16 "In7.Cu" signal "GND3")
		(18 "In8.Cu" signal "VCC")
		(20 "In9.Cu" signal "VCC1")
		(22 "In10.Cu" signal "GND4")
		(24 "In11.Cu" signal "IN4")
		(26 "In12.Cu" signal "GND5")
		(28 "In13.Cu" signal "IN5")
		(30 "In14.Cu" signal "GND6")
		(32 "In15.Cu" signal "IN6")
		(34 "In16.Cu" signal "GND7")
		(2 "B.Cu" signal "BOTTOM")
		(9 "F.Adhes" user "F.Adhesive")
		(11 "B.Adhes" user "B.Adhesive")
		(13 "F.Paste" user "Package Geometry/Pastemask Top")
		(15 "B.Paste" user "Package Geometry/Pastemask Bottom")
		(5 "F.SilkS" user "Ref Des/Silkscreen Top")
		(7 "B.SilkS" user "Ref Des/Silkscreen Bottom")
		(1 "F.Mask" user "Board Geometry/Soldermask Top")
		(3 "B.Mask" user "Board Geometry/Soldermask Bottom")
		(17 "Dwgs.User" user "User.Drawings")
		(19 "Cmts.User" user "User.Comments")
		(21 "Eco1.User" user "User.Eco1")
		(23 "Eco2.User" user "User.Eco2")
		(25 "Edge.Cuts" user "Board Geometry/Outline")
		(27 "Margin" user)
		(31 "F.CrtYd" user "Package Geometry/Place Bound Top")
		(29 "B.CrtYd" user "Package Geometry/Place Bound Bottom")
		(35 "F.Fab" user "Ref Des/Assembly Top")
		(33 "B.Fab" user "Ref Des/Assembly Bottom")
	)
	(footprint ""
		(layer "B.Cu")
		(at 378.099574 8.003794)
		(property "Reference" "J116"
			(at 4.524756 1.521206 270)
			(unlocked yes)
			(layer "B.SilkS")
			(effects
				(font
					(size 0.7874 0.5842)
					(thickness 0.1524)
				)
				(justify left mirror)
			)
		)
		(property "Value" ""
			(at 0 0 0)
			(layer "B.Fab")
			(effects
				(font
					(size 1.27 1.27)
				)
				(justify mirror)
			)
		)
		(duplicate_pad_numbers_are_jumpers no)
		(fp_line
			(start -1.2192 -2.1082)
			(end -1.2192 2.1082)
			(stroke
				(width 0.1524)
				(type default)
			)
			(layer "B.SilkS")
		)
		(fp_line
			(start -1.2192 2.1082)
			(end 1.2192 2.1082)
			(stroke
				(width 0.1524)
				(type default)
			)
			(layer "B.SilkS")
		)
		(fp_line
			(start 1.2192 -2.1082)
			(end -1.2192 -2.1082)
			(stroke
				(width 0.1524)
				(type default)
			)
			(layer "B.SilkS")
		)
		(fp_line
			(start 1.2192 2.1082)
			(end 1.2192 -2.1082)
			(stroke
				(width 0.1524)
				(type default)
			)
			(layer "B.SilkS")
		)
		(pad "" np_thru_hole circle
			(at -3.4671 -1.27 270)
			(size 1.0414 1.0414)
			(drill 1.0414)
			(layers "*.Cu" "*.Mask")
			(clearance 0.381)
			(thermal_gap 0.381)
		)
		(pad "" np_thru_hole circle
			(at -3.4671 1.27 270)
			(size 1.0414 1.0414)
			(drill 1.0414)
			(layers "*.Cu" "*.Mask")
			(clearance 0.381)
			(thermal_gap 0.381)
		)
		(pad "" np_thru_hole circle
			(at 2.8829 -1.27 270)
			(size 1.0414 1.0414)
			(drill 1.0414)
			(layers "*.Cu" "*.Mask")
			(clearance 0.381)
			(thermal_gap 0.381)
		)
		(pad "" np_thru_hole circle
			(at 2.8829 1.27 270)
			(size 1.0414 1.0414)
			(drill 1.0414)
			(layers "*.Cu" "*.Mask")
			(clearance 0.381)
			(thermal_gap 0.381)
		)
		(pad "1" smd rect
			(at -0.8255 -0.249936 270)
			(size 0.3048 0.508)
			(layers "B.Cu" "B.Mask" "B.Paste")
			(net "DELTA_L_85_5INCH_IN5_DN")
		)
		(pad "2" smd rect
			(at -0.8255 0.249936 270)
			(size 0.3048 0.508)
			(layers "B.Cu" "B.Mask" "B.Paste")
			(net "DELTA_L_85_5INCH_IN5_DP")
		)
		(pad "3" smd circle
			(at 0 0 180)
			(size 0 0)
			(layers "B.Cu" "B.Mask" "B.Paste")
			(net "DELTA_L_GND_1")
		)
		(zone
			(layers "F.Cu" "B.Cu" "In1.Cu" "In2.Cu" "In3.Cu" "In4.Cu" "In5.Cu" "In6.Cu"
				"In7.Cu" "In8.Cu" "In9.Cu" "In10.Cu" "In11.Cu" "In12.Cu" "In13.Cu" "In14.Cu"
				"In15.Cu" "In16.Cu"
			)
			(hatch none 0.5)
			(connect_pads
				(clearance 0)
			)
			(min_thickness 0.25)
			(keepout
				(tracks not_allowed)
				(vias allowed)
				(pads allowed)
				(copperpour not_allowed)
				(footprints allowed)
			)
			(placement
				(enabled no)
				(sheetname "")
			)
			(fill
				(thermal_gap 0.5)
				(thermal_bridge_width 0.5)
				(island_removal_mode 0)
			)
			(polygon
				(pts
					(arc
						(start 375.559574 6.733794)
						(mid 373.705374 6.733794)
						(end 375.559574 6.733794)
					)
				)
			)
		)
		(zone
			(layers "F.Cu" "B.Cu" "In1.Cu" "In2.Cu" "In3.Cu" "In4.Cu" "In5.Cu" "In6.Cu"
				"In7.Cu" "In8.Cu" "In9.Cu" "In10.Cu" "In11.Cu" "In12.Cu" "In13.Cu" "In14.Cu"
				"In15.Cu" "In16.Cu"
			)
			(hatch none 0.5)
			(connect_pads
				(clearance 0)
			)
			(min_thickness 0.25)
			(keepout
				(tracks not_allowed)
				(vias allowed)
				(pads allowed)
				(copperpour not_allowed)
				(footprints allowed)
			)
			(placement
				(enabled no)
				(sheetname "")
			)
			(fill
				(thermal_gap 0.5)
				(thermal_bridge_width 0.5)
				(island_removal_mode 0)
			)
			(polygon
				(pts
					(arc
						(start 375.559574 9.273794)
						(mid 373.705374 9.273794)
						(end 375.559574 9.273794)
					)
				)
			)
		)
		(zone
			(layers "F.Cu" "B.Cu" "In1.Cu" "In2.Cu" "In3.Cu" "In4.Cu" "In5.Cu" "In6.Cu"
				"In7.Cu" "In8.Cu" "In9.Cu" "In10.Cu" "In11.Cu" "In12.Cu" "In13.Cu" "In14.Cu"
				"In15.Cu" "In16.Cu"
			)
			(hatch none 0.5)
			(connect_pads
				(clearance 0)
			)
			(min_thickness 0.25)
			(keepout
				(tracks not_allowed)
				(vias allowed)
				(pads allowed)
				(copperpour not_allowed)
				(footprints allowed)
			)
			(placement
				(enabled no)
				(sheetname "")
			)
			(fill
				(thermal_gap 0.5)
				(thermal_bridge_width 0.5)
				(island_removal_mode 0)
			)
			(polygon
				(pts
					(arc
						(start 381.909574 6.733794)
						(mid 380.055374 6.733794)
						(end 381.909574 6.733794)
					)
				)
			)
		)
		(zone
			(layers "F.Cu" "B.Cu" "In1.Cu" "In2.Cu" "In3.Cu" "In4.Cu" "In5.Cu" "In6.Cu"
				"In7.Cu" "In8.Cu" "In9.Cu" "In10.Cu" "In11.Cu" "In12.Cu" "In13.Cu" "In14.Cu"
				"In15.Cu" "In16.Cu"
			)
			(hatch none 0.5)
			(connect_pads
				(clearance 0)
			)
			(min_thickness 0.25)
			(keepout
				(tracks not_allowed)
				(vias allowed)
				(pads allowed)
				(copperpour not_allowed)
				(footprints allowed)
			)
			(placement
				(enabled no)
				(sheetname "")
			)
			(fill
				(thermal_gap 0.5)
				(thermal_bridge_width 0.5)
				(island_removal_mode 0)
			)
			(polygon
				(pts
					(arc
						(start 381.909574 9.273794)
						(mid 380.055374 9.273794)
						(end 381.909574 9.273794)
					)
				)
			)
		)
		(zone
			(layer "B.Cu")
			(hatch none 0.5)
			(connect_pads
				(clearance 0)
			)
			(min_thickness 0.25)
			(keepout
				(tracks not_allowed)
				(vias allowed)
				(pads allowed)
				(copperpour not_allowed)
				(footprints allowed)
			)
			(placement
				(enabled no)
				(sheetname "")
			)
			(fill
				(thermal_gap 0.5)
				(thermal_bridge_width 0.5)
				(island_removal_mode 0)
			)
			(polygon
				(pts
					(xy 376.981974 7.455154) (xy 376.981974 7.550658) (xy 377.578874 7.550658) (xy 377.578874 7.957058)
					(xy 376.981974 7.957058) (xy 376.981974 8.05053) (xy 377.578874 8.05053) (xy 377.578874 8.45693)
					(xy 376.981974 8.45693) (xy 376.981974 8.552434) (xy 377.680474 8.552434) (xy 377.680474 7.455154)
				)
			)
		)
	)
)
